(kicad_pcb
	(version 20260206)
	(generator "pcbnew")
	(generator_version "10.0")
	(general
		(thickness 1.6)
		(legacy_teardrops no)
	)
	(paper "A4")
	(title_block
		(title "15969-1a.1015WZS0858.brd")
		(comment 1 "Tioga Pass / footprints 116-122 of 295")
	)
	(layers
		(0 "F.Cu" signal "TOP")
		(4 "In1.Cu" signal "L2GND")
		(6 "In2.Cu" signal "L3")
		(8 "In3.Cu" signal "L4")
		(10 "In4.Cu" signal "L5GND")
		(2 "B.Cu" signal "BOTTOM")
		(9 "F.Adhes" user "F.Adhesive")
		(11 "B.Adhes" user "B.Adhesive")
		(13 "F.Paste" user "Package Geometry/Pastemask Top")
		(15 "B.Paste" user "Package Geometry/Pastemask Bottom")
		(5 "F.SilkS" user "Ref Des/Silkscreen Top")
		(7 "B.SilkS" user "Ref Des/Silkscreen Bottom")
		(1 "F.Mask" user "Board Geometry/Soldermask Top")
		(3 "B.Mask" user "Board Geometry/Soldermask Bottom")
		(17 "Dwgs.User" user "User.Drawings")
		(19 "Cmts.User" user "User.Comments")
		(21 "Eco1.User" user "User.Eco1")
		(23 "Eco2.User" user "User.Eco2")
		(25 "Edge.Cuts" user "Board Geometry/Outline")
		(27 "Margin" user)
		(31 "F.CrtYd" user "Package Geometry/Place Bound Top")
		(29 "B.CrtYd" user "Package Geometry/Place Bound Bottom")
		(35 "F.Fab" user "Ref Des/Assembly Top")
		(33 "B.Fab" user "Ref Des/Assembly Bottom")
	)
	(footprint ""
		(layer "F.Cu")
		(at 132.334 -31.7754 180)
		(property "Reference" "XU1"
			(at 0 0 180)
			(layer "F.SilkS")
			(hide yes)
			(effects
				(font
					(size 1.27 1.27)
				)
			)
		)
		(property "Value" "XTAL-24MHZ-87-GP"
			(at -0.0889 -3.0988 180)
			(unlocked yes)
			(layer "F.Fab")
			(hide yes)
			(effects
				(font
					(size 1.016 1.016)
					(thickness 0.1524)
				)
			)
		)
		(property "Device Type" "OSC-3225-4P-4H30"
			(at -0.0889 -4.6228 180)
			(unlocked yes)
			(layer "F.Fab")
			(hide yes)
			(effects
				(font
					(size 1.016 1.016)
					(thickness 0.1524)
				)
			)
		)
		(duplicate_pad_numbers_are_jumpers no)
		(fp_line
			(start 2.1209 1.5494)
			(end 2.1209 -1.5494)
			(stroke
				(width 0.1524)
				(type default)
			)
			(layer "F.SilkS")
		)
		(fp_line
			(start 2.1209 -1.5494)
			(end -2.1209 -1.5494)
			(stroke
				(width 0.1524)
				(type default)
			)
			(layer "F.SilkS")
		)
		(fp_line
			(start -1.143 1.651)
			(end -2.2098 1.651)
			(stroke
				(width 0.3302)
				(type default)
			)
			(layer "F.SilkS")
		)
		(fp_line
			(start -2.1209 1.5494)
			(end 2.1209 1.5494)
			(stroke
				(width 0.1524)
				(type default)
			)
			(layer "F.SilkS")
		)
		(fp_line
			(start -2.1209 -1.5494)
			(end -2.1209 1.5494)
			(stroke
				(width 0.1524)
				(type default)
			)
			(layer "F.SilkS")
		)
		(fp_line
			(start -2.2098 1.651)
			(end -2.2098 0.6604)
			(stroke
				(width 0.3302)
				(type default)
			)
			(layer "F.SilkS")
		)
		(fp_poly
			(pts
				(xy -2.6289 1.1938) (xy -2.6289 0.3302) (xy -2.1971 0.762)
			)
			(stroke
				(width 0)
				(type default)
			)
			(fill yes)
			(layer "F.SilkS")
		)
		(fp_rect
			(start -1.6002 1.2446)
			(end 1.6002 -1.2446)
			(stroke
				(width 0)
				(type default)
			)
			(fill no)
			(layer "F.CrtYd")
		)
		(fp_poly
			(pts
				(xy -2.3749 1.8034) (xy -2.3749 -1.8034) (xy 2.3749 -1.8034) (xy 2.3749 1.8034) (xy 0.00254 1.8034)
				(xy 0.00254 1.2446) (xy 1.6002 1.2446) (xy 1.6002 -1.2446) (xy -1.6002 -1.2446) (xy -1.6002 1.2446)
				(xy -0.00254 1.2446) (xy -0.00254 1.8034)
			)
			(stroke
				(width 0)
				(type default)
			)
			(fill no)
			(layer "F.CrtYd")
		)
		(fp_rect
			(start -2.3749 1.8034)
			(end 2.3749 -1.8034)
			(stroke
				(width 0)
				(type default)
			)
			(fill no)
			(layer "F.Fab")
		)
		(pad "1" smd rect
			(at -1.171448 0.756412 180)
			(size 1.397 1.0668)
			(layers "F.Cu" "F.Mask" "F.Paste")
			(net "USB_HUB_XTAL_OUT")
		)
		(pad "2" smd rect
			(at 1.171448 0.756412 180)
			(size 1.397 1.0668)
			(layers "F.Cu" "F.Mask" "F.Paste")
			(net "GND")
		)
		(pad "3" smd rect
			(at 1.171448 -0.756412 180)
			(size 1.397 1.0668)
			(layers "F.Cu" "F.Mask" "F.Paste")
			(net "USB_HUB_XTAL_IN")
		)
		(pad "4" smd rect
			(at -1.171448 -0.756412 180)
			(size 1.397 1.0668)
			(layers "F.Cu" "F.Mask" "F.Paste")
			(net "GND")
		)
		(zone
			(layer "F.Cu")
			(hatch none 0.5)
			(connect_pads
				(clearance 0)
			)
			(min_thickness 0.25)
			(keepout
				(tracks not_allowed)
				(vias allowed)
				(pads allowed)
				(copperpour not_allowed)
				(footprints allowed)
			)
			(placement
				(enabled no)
				(sheetname "")
			)
			(fill
				(thermal_gap 0.5)
				(thermal_bridge_width 0.5)
				(island_removal_mode 0)
			)
			(polygon
				(pts
					(xy 132.3848 -31.8262) (xy 132.2832 -31.8262) (xy 132.2832 -31.7246) (xy 132.3848 -31.7246)
				)
			)
		)
		(zone
			(layer "F.Cu")
			(hatch none 0.5)
			(connect_pads
				(clearance 0)
			)
			(min_thickness 0.25)
			(keepout
				(tracks allowed)
				(vias not_allowed)
				(pads allowed)
				(copperpour not_allowed)
				(footprints allowed)
			)
			(placement
				(enabled no)
				(sheetname "")
			)
			(fill
				(thermal_gap 0.5)
				(thermal_bridge_width 0.5)
				(island_removal_mode 0)
			)
			(polygon
				(pts
					(xy 132.806948 -30.485588) (xy 131.861052 -30.485588) (xy 131.861052 -31.552388) (xy 130.464052 -31.552388)
					(xy 130.464052 -31.998412) (xy 131.861052 -31.998412) (xy 131.861052 -33.065212) (xy 132.806948 -33.065212)
					(xy 132.806948 -31.998412) (xy 134.203948 -31.998412) (xy 134.203948 -31.552388) (xy 132.806948 -31.552388)
				)
			)
		)
	)
	(footprint ""
		(layer "F.Cu")
		(at 26.035 -12.0142 -90)
		(property "Reference" "C15"
			(at 0 0 270)
			(layer "F.SilkS")
			(hide yes)
			(effects
				(font
					(size 1.27 1.27)
				)
			)
		)
		(property "Value" "SCD1U25V3KX-GP"
			(at 0 -2.8194 270)
			(unlocked yes)
			(layer "F.Fab")
			(hide yes)
			(effects
				(font
					(size 1.016 1.016)
					(thickness 0.1524)
				)
			)
		)
		(property "Device Type" "C603H36"
			(at 0 -4.3434 270)
			(unlocked yes)
			(layer "F.Fab")
			(hide yes)
			(effects
				(font
					(size 1.016 1.016)
					(thickness 0.1524)
				)
			)
		)
		(duplicate_pad_numbers_are_jumpers no)
		(fp_line
			(start 0.508 0)
			(end -0.508 0)
			(stroke
				(width 0.2032)
				(type default)
			)
			(layer "F.SilkS")
		)
		(fp_rect
			(start -0.5842 1.3335)
			(end 0.5842 -1.3335)
			(stroke
				(width 0)
				(type default)
			)
			(fill no)
			(layer "F.CrtYd")
		)
		(fp_rect
			(start -0.5842 1.3335)
			(end 0.5842 -1.3335)
			(stroke
				(width 0)
				(type default)
			)
			(fill no)
			(layer "F.Fab")
		)
		(pad "1" smd custom
			(at 0 -0.762 270)
			(size 0.2159 0.2159)
			(layers "F.Cu" "F.Mask" "F.Paste")
			(net "P12V_SLOT2")
			(options
				(clearance outline)
				(anchor circle)
			)
			(primitives
				(gr_poly
					(pts
						(arc
							(start -0.3302 -0.4318)
							(mid -0.402042 -0.402042)
							(end -0.4318 -0.3302)
						)
						(arc
							(start -0.4318 0.3302)
							(mid -0.402042 0.402042)
							(end -0.3302 0.4318)
						)
						(arc
							(start 0.3302 0.4318)
							(mid 0.402042 0.402042)
							(end 0.4318 0.3302)
						)
						(arc
							(start 0.4318 -0.3302)
							(mid 0.402042 -0.402042)
							(end 0.3302 -0.4318)
						)
					)
					(width 0)
					(fill yes)
				)
			)
		)
		(pad "2" smd custom
			(at 0 0.762 270)
			(size 0.2159 0.2159)
			(layers "F.Cu" "F.Mask" "F.Paste")
			(net "GND")
			(options
				(clearance outline)
				(anchor circle)
			)
			(primitives
				(gr_poly
					(pts
						(arc
							(start -0.3302 -0.4318)
							(mid -0.402042 -0.402042)
							(end -0.4318 -0.3302)
						)
						(arc
							(start -0.4318 0.3302)
							(mid -0.402042 0.402042)
							(end -0.3302 0.4318)
						)
						(arc
							(start 0.3302 0.4318)
							(mid 0.402042 0.402042)
							(end 0.4318 0.3302)
						)
						(arc
							(start 0.4318 -0.3302)
							(mid 0.402042 -0.402042)
							(end 0.3302 -0.4318)
						)
					)
					(width 0)
					(fill yes)
				)
			)
		)
	)
	(footprint ""
		(layer "F.Cu")
		(at 131.7244 -12.5476 90)
		(property "Reference" "R125"
			(at 0 0 90)
			(layer "F.SilkS")
			(hide yes)
			(effects
				(font
					(size 1.27 1.27)
				)
			)
		)
		(property "Value" "10KR2F-2-GP"
			(at 0.064008 -3.993896 90)
			(unlocked yes)
			(layer "F.Fab")
			(hide yes)
			(effects
				(font
					(size 1.016 1.016)
					(thickness 0.1524)
				)
			)
		)
		(property "Device Type" "R402H16"
			(at 0.064008 -5.517896 90)
			(unlocked yes)
			(layer "F.Fab")
			(hide yes)
			(effects
				(font
					(size 1.016 1.016)
					(thickness 0.1524)
				)
			)
		)
		(duplicate_pad_numbers_are_jumpers no)
		(fp_line
			(start 0.508 -0.9398)
			(end -0.508 -0.9398)
			(stroke
				(width 0.1524)
				(type default)
			)
			(layer "F.SilkS")
		)
		(fp_line
			(start -0.508 -0.9398)
			(end -0.508 0.9398)
			(stroke
				(width 0.1524)
				(type default)
			)
			(layer "F.SilkS")
		)
		(fp_rect
			(start -0.508 0.9398)
			(end 0.508 -0.9398)
			(stroke
				(width 0)
				(type default)
			)
			(fill no)
			(layer "F.CrtYd")
		)
		(fp_rect
			(start -0.508 0.9398)
			(end 0.508 -0.9398)
			(stroke
				(width 0)
				(type default)
			)
			(fill no)
			(layer "F.Fab")
		)
		(pad "1" smd custom
			(at 0 -0.4445 90)
			(size 0.1397 0.1397)
			(layers "F.Cu" "F.Mask" "F.Paste")
			(net "GPIO_B_IO1_4")
			(options
				(clearance outline)
				(anchor circle)
			)
			(primitives
				(gr_poly
					(pts
						(arc
							(start -0.1778 -0.2794)
							(mid -0.249642 -0.249642)
							(end -0.2794 -0.1778)
						)
						(arc
							(start -0.2794 0.1778)
							(mid -0.249642 0.249642)
							(end -0.1778 0.2794)
						)
						(arc
							(start 0.1778 0.2794)
							(mid 0.249642 0.249642)
							(end 0.2794 0.1778)
						)
						(arc
							(start 0.2794 -0.1778)
							(mid 0.249642 -0.249642)
							(end 0.1778 -0.2794)
						)
					)
					(width 0)
					(fill yes)
				)
			)
		)
		(pad "2" smd custom
			(at 0 0.4445 90)
			(size 0.1397 0.1397)
			(layers "F.Cu" "F.Mask" "F.Paste")
			(net "GND")
			(options
				(clearance outline)
				(anchor circle)
			)
			(primitives
				(gr_poly
					(pts
						(arc
							(start -0.1778 -0.2794)
							(mid -0.249642 -0.249642)
							(end -0.2794 -0.1778)
						)
						(arc
							(start -0.2794 0.1778)
							(mid -0.249642 0.249642)
							(end -0.1778 0.2794)
						)
						(arc
							(start 0.1778 0.2794)
							(mid 0.249642 0.249642)
							(end 0.2794 0.1778)
						)
						(arc
							(start 0.2794 -0.1778)
							(mid 0.249642 -0.249642)
							(end 0.1778 -0.2794)
						)
					)
					(width 0)
					(fill yes)
				)
			)
		)
	)
	(footprint ""
		(layer "F.Cu")
		(at 15.145512 -17.724882 -135)
		(property "Reference" "R83"
			(at 0 0 225)
			(layer "F.SilkS")
			(hide yes)
			(effects
				(font
					(size 1.27 1.27)
				)
			)
		)
		(property "Value" "D001R6F-L-GP"
			(at -0.126981 -3.733736 225)
			(unlocked yes)
			(layer "F.Fab")
			(hide yes)
			(effects
				(font
					(size 1.016 1.016)
					(thickness 0.1524)
				)
			)
		)
		(property "Device Type" "R1206H36"
			(at -0.12716 -5.257685 225)
			(unlocked yes)
			(layer "F.Fab")
			(hide yes)
			(effects
				(font
					(size 1.016 1.016)
					(thickness 0.1524)
				)
			)
		)
		(duplicate_pad_numbers_are_jumpers no)
		(fp_line
			(start 1.016026 2.235186)
			(end -1.016026 2.235186)
			(stroke
				(width 0.1524)
				(type default)
			)
			(layer "F.SilkS")
		)
		(fp_line
			(start -1.016026 2.235186)
			(end -1.016026 -2.235186)
			(stroke
				(width 0.1524)
				(type default)
			)
			(layer "F.SilkS")
		)
		(fp_line
			(start 1.016026 -2.235186)
			(end 1.016026 2.235186)
			(stroke
				(width 0.1524)
				(type default)
			)
			(layer "F.SilkS")
		)
		(fp_line
			(start -1.016026 -2.235186)
			(end 1.016026 -2.235186)
			(stroke
				(width 0.1524)
				(type default)
			)
			(layer "F.SilkS")
		)
		(fp_poly
			(pts
				(xy -0.800141 -1.599939) (xy 0.80006 -1.599939) (xy 0.800059 1.600461) (xy -0.800141 1.600461)
			)
			(stroke
				(width 0)
				(type default)
			)
			(fill no)
			(layer "F.CrtYd")
		)
		(fp_poly
			(pts
				(xy -1.092358 2.311518) (xy -1.092179 -2.311338) (xy 1.092179 -2.311338) (xy 1.092179 1.58753) (xy 0.800141 1.58753)
				(xy 0.800141 -1.600102) (xy -0.800141 -1.600102) (xy -0.800141 1.600461) (xy 1.092179 1.600461)
				(xy 1.092358 2.311518)
			)
			(stroke
				(width 0)
				(type default)
			)
			(fill no)
			(layer "F.CrtYd")
		)
		(fp_poly
			(pts
				(xy -1.092358 -2.311282) (xy 1.092042 -2.311282) (xy 1.092042 2.311518) (xy -1.092358 2.311518)
			)
			(stroke
				(width 0)
				(type default)
			)
			(fill no)
			(layer "F.Fab")
		)
		(pad "1" smd rect
			(at 0 -1.397 225)
			(size 1.651 1.27)
			(layers "F.Cu" "F.Mask" "F.Paste")
			(net "P12V")
		)
		(pad "2" smd rect
			(at 0 1.397 225)
			(size 1.651 1.27)
			(layers "F.Cu" "F.Mask" "F.Paste")
			(net "P12V_SLOT2")
		)
	)
	(footprint ""
		(layer "F.Cu")
		(at 21.5138 -15.748)
		(property "Reference" "R84"
			(at 0 0 0)
			(layer "F.SilkS")
			(hide yes)
			(effects
				(font
					(size 1.27 1.27)
				)
			)
		)
		(property "Value" "10KR2F-2-GP"
			(at 0.064008 -3.993896 0)
			(unlocked yes)
			(layer "F.Fab")
			(hide yes)
			(effects
				(font
					(size 1.016 1.016)
					(thickness 0.1524)
				)
			)
		)
		(property "Device Type" "R402H16"
			(at 0.064008 -5.517896 0)
			(unlocked yes)
			(layer "F.Fab")
			(hide yes)
			(effects
				(font
					(size 1.016 1.016)
					(thickness 0.1524)
				)
			)
		)
		(duplicate_pad_numbers_are_jumpers no)
		(fp_line
			(start -0.508 -0.9398)
			(end -0.508 0.9398)
			(stroke
				(width 0.1524)
				(type default)
			)
			(layer "F.SilkS")
		)
		(fp_line
			(start 0.508 -0.9398)
			(end -0.508 -0.9398)
			(stroke
				(width 0.1524)
				(type default)
			)
			(layer "F.SilkS")
		)
		(fp_rect
			(start -0.508 0.9398)
			(end 0.508 -0.9398)
			(stroke
				(width 0)
				(type default)
			)
			(fill no)
			(layer "F.CrtYd")
		)
		(fp_rect
			(start -0.508 0.9398)
			(end 0.508 -0.9398)
			(stroke
				(width 0)
				(type default)
			)
			(fill no)
			(layer "F.Fab")
		)
		(pad "1" smd custom
			(at 0 -0.4445)
			(size 0.1397 0.1397)
			(layers "F.Cu" "F.Mask" "F.Paste")
			(net "SLOT2_VMONITOR_A0")
			(options
				(clearance outline)
				(anchor circle)
			)
			(primitives
				(gr_poly
					(pts
						(arc
							(start -0.1778 -0.2794)
							(mid -0.249642 -0.249642)
							(end -0.2794 -0.1778)
						)
						(arc
							(start -0.2794 0.1778)
							(mid -0.249642 0.249642)
							(end -0.1778 0.2794)
						)
						(arc
							(start 0.1778 0.2794)
							(mid 0.249642 0.249642)
							(end 0.2794 0.1778)
						)
						(arc
							(start 0.2794 -0.1778)
							(mid 0.249642 -0.249642)
							(end 0.1778 -0.2794)
						)
					)
					(width 0)
					(fill yes)
				)
			)
		)
		(pad "2" smd custom
			(at 0 0.4445)
			(size 0.1397 0.1397)
			(layers "F.Cu" "F.Mask" "F.Paste")
			(net "GND")
			(options
				(clearance outline)
				(anchor circle)
			)
			(primitives
				(gr_poly
					(pts
						(arc
							(start -0.1778 -0.2794)
							(mid -0.249642 -0.249642)
							(end -0.2794 -0.1778)
						)
						(arc
							(start -0.2794 0.1778)
							(mid -0.249642 0.249642)
							(end -0.1778 0.2794)
						)
						(arc
							(start 0.1778 0.2794)
							(mid 0.249642 0.249642)
							(end 0.2794 0.1778)
						)
						(arc
							(start 0.2794 -0.1778)
							(mid 0.249642 -0.249642)
							(end 0.1778 -0.2794)
						)
					)
					(width 0)
					(fill yes)
				)
			)
		)
	)
	(footprint ""
		(layer "F.Cu")
		(at 88.138 -23.9014)
		(property "Reference" "R74"
			(at 0 0 0)
			(layer "F.SilkS")
			(hide yes)
			(effects
				(font
					(size 1.27 1.27)
				)
			)
		)
		(property "Value" "4K7R2F-GP"
			(at 0.064008 -3.993896 0)
			(unlocked yes)
			(layer "F.Fab")
			(hide yes)
			(effects
				(font
					(size 1.016 1.016)
					(thickness 0.1524)
				)
			)
		)
		(property "Device Type" "R402H16"
			(at 0.064008 -5.517896 0)
			(unlocked yes)
			(layer "F.Fab")
			(hide yes)
			(effects
				(font
					(size 1.016 1.016)
					(thickness 0.1524)
				)
			)
		)
		(duplicate_pad_numbers_are_jumpers no)
		(fp_line
			(start -0.508 -0.9398)
			(end -0.508 0.9398)
			(stroke
				(width 0.1524)
				(type default)
			)
			(layer "F.SilkS")
		)
		(fp_line
			(start 0.508 -0.9398)
			(end -0.508 -0.9398)
			(stroke
				(width 0.1524)
				(type default)
			)
			(layer "F.SilkS")
		)
		(fp_rect
			(start -0.508 0.9398)
			(end 0.508 -0.9398)
			(stroke
				(width 0)
				(type default)
			)
			(fill no)
			(layer "F.CrtYd")
		)
		(fp_rect
			(start -0.508 0.9398)
			(end 0.508 -0.9398)
			(stroke
				(width 0)
				(type default)
			)
			(fill no)
			(layer "F.Fab")
		)
		(pad "1" smd custom
			(at 0 -0.4445)
			(size 0.1397 0.1397)
			(layers "F.Cu" "F.Mask" "F.Paste")
			(net "P3V3_STBY")
			(options
				(clearance outline)
				(anchor circle)
			)
			(primitives
				(gr_poly
					(pts
						(arc
							(start -0.1778 -0.2794)
							(mid -0.249642 -0.249642)
							(end -0.2794 -0.1778)
						)
						(arc
							(start -0.2794 0.1778)
							(mid -0.249642 0.249642)
							(end -0.1778 0.2794)
						)
						(arc
							(start 0.1778 0.2794)
							(mid 0.249642 0.249642)
							(end 0.2794 0.1778)
						)
						(arc
							(start 0.2794 -0.1778)
							(mid 0.249642 -0.249642)
							(end 0.1778 -0.2794)
						)
					)
					(width 0)
					(fill yes)
				)
			)
		)
		(pad "2" smd custom
			(at 0 0.4445)
			(size 0.1397 0.1397)
			(layers "F.Cu" "F.Mask" "F.Paste")
			(net "RESET_O_1")
			(options
				(clearance outline)
				(anchor circle)
			)
			(primitives
				(gr_poly
					(pts
						(arc
							(start -0.1778 -0.2794)
							(mid -0.249642 -0.249642)
							(end -0.2794 -0.1778)
						)
						(arc
							(start -0.2794 0.1778)
							(mid -0.249642 0.249642)
							(end -0.1778 0.2794)
						)
						(arc
							(start 0.1778 0.2794)
							(mid 0.249642 0.249642)
							(end 0.2794 0.1778)
						)
						(arc
							(start 0.2794 -0.1778)
							(mid 0.249642 -0.249642)
							(end 0.1778 -0.2794)
						)
					)
					(width 0)
					(fill yes)
				)
			)
		)
	)
	(footprint ""
		(layer "F.Cu")
		(at 129.2098 -10.7696 180)
		(property "Reference" "R118"
			(at 0 0 180)
			(layer "F.SilkS")
			(hide yes)
			(effects
				(font
					(size 1.27 1.27)
				)
			)
		)
		(property "Value" "10KR2F-2-GP"
			(at 0.064008 -3.993896 180)
			(unlocked yes)
			(layer "F.Fab")
			(hide yes)
			(effects
				(font
					(size 1.016 1.016)
					(thickness 0.1524)
				)
			)
		)
		(property "Device Type" "R402H16"
			(at 0.064008 -5.517896 180)
			(unlocked yes)
			(layer "F.Fab")
			(hide yes)
			(effects
				(font
					(size 1.016 1.016)
					(thickness 0.1524)
				)
			)
		)
		(duplicate_pad_numbers_are_jumpers no)
		(fp_line
			(start 0.508 -0.9398)
			(end -0.508 -0.9398)
			(stroke
				(width 0.1524)
				(type default)
			)
			(layer "F.SilkS")
		)
		(fp_line
			(start -0.508 -0.9398)
			(end -0.508 0.9398)
			(stroke
				(width 0.1524)
				(type default)
			)
			(layer "F.SilkS")
		)
		(fp_rect
			(start -0.508 0.9398)
			(end 0.508 -0.9398)
			(stroke
				(width 0)
				(type default)
			)
			(fill no)
			(layer "F.CrtYd")
		)
		(fp_rect
			(start -0.508 0.9398)
			(end 0.508 -0.9398)
			(stroke
				(width 0)
				(type default)
			)
			(fill no)
			(layer "F.Fab")
		)
		(pad "1" smd custom
			(at 0 -0.4445 180)
			(size 0.1397 0.1397)
			(layers "F.Cu" "F.Mask" "F.Paste")
			(net "P3V3_STBY")
			(options
				(clearance outline)
				(anchor circle)
			)
			(primitives
				(gr_poly
					(pts
						(arc
							(start -0.1778 -0.2794)
							(mid -0.249642 -0.249642)
							(end -0.2794 -0.1778)
						)
						(arc
							(start -0.2794 0.1778)
							(mid -0.249642 0.249642)
							(end -0.1778 0.2794)
						)
						(arc
							(start 0.1778 0.2794)
							(mid 0.249642 0.249642)
							(end 0.2794 0.1778)
						)
						(arc
							(start 0.2794 -0.1778)
							(mid 0.249642 -0.249642)
							(end 0.1778 -0.2794)
						)
					)
					(width 0)
					(fill yes)
				)
			)
		)
		(pad "2" smd custom
			(at 0 0.4445 180)
			(size 0.1397 0.1397)
			(layers "F.Cu" "F.Mask" "F.Paste")
			(net "GPIO_B_IO1_0")
			(options
				(clearance outline)
				(anchor circle)
			)
			(primitives
				(gr_poly
					(pts
						(arc
							(start -0.1778 -0.2794)
							(mid -0.249642 -0.249642)
							(end -0.2794 -0.1778)
						)
						(arc
							(start -0.2794 0.1778)
							(mid -0.249642 0.249642)
							(end -0.1778 0.2794)
						)
						(arc
							(start 0.1778 0.2794)
							(mid 0.249642 0.249642)
							(end 0.2794 0.1778)
						)
						(arc
							(start 0.2794 -0.1778)
							(mid 0.249642 -0.249642)
							(end 0.1778 -0.2794)
						)
					)
					(width 0)
					(fill yes)
				)
			)
		)
	)
)
